# SCM (Grand Teton) — schematic netlist excerpt (pin names and nets, part order shuffled) for the footprints in the layout excerpt that follows; sources: Cadence DE-HDL packaged netlist, KiCad conversion of 12092022_DA0F0TMDCD0_F0T_Management_Board_D_brd_V3_OCP.brd

C243  Q_CAP  0.1UF 25V 10% X7R  pkg 0402  page 41 : A = VCCIO1 ; B = GND
L7  Q_INDUCTOR  BLM18PG121SN1D/2000MA IND  pkg SMLF  page 17 : \1\ = P3V3_AUX ; \2\ = P3V3_STBY_DACAV33

(kicad_pcb
	(version 20260206)
	(generator "pcbnew")
	(generator_version "10.0")
	(general
		(thickness 1.6)
		(legacy_teardrops no)
	)
	(paper "A4")
	(title_block
		(title "12092022_DA0F0TMDCD0_F0T_Management_Board_D_brd_V3_OCP.brd")
		(comment 1 "Grand Teton / footprints 913-914 of 1440")
	)
	(layers
		(0 "F.Cu" signal "TOP")
		(4 "In1.Cu" signal "GND")
		(6 "In2.Cu" signal "IN1")
		(8 "In3.Cu" signal "GND1")
		(10 "In4.Cu" signal "IN2")
		(12 "In5.Cu" signal "VCC")
		(14 "In6.Cu" signal "VCC1")
		(16 "In7.Cu" signal "IN3")
		(18 "In8.Cu" signal "GND2")
		(20 "In9.Cu" signal "IN4")
		(22 "In10.Cu" signal "GND3")
		(2 "B.Cu" signal "BOTTOM")
		(9 "F.Adhes" user "F.Adhesive")
		(11 "B.Adhes" user "B.Adhesive")
		(13 "F.Paste" user "Package Geometry/Pastemask Top")
		(15 "B.Paste" user "Package Geometry/Pastemask Bottom")
		(5 "F.SilkS" user "Ref Des/Silkscreen Top")
		(7 "B.SilkS" user "Ref Des/Silkscreen Bottom")
		(1 "F.Mask" user "Board Geometry/Soldermask Top")
		(3 "B.Mask" user "Board Geometry/Soldermask Bottom")
		(17 "Dwgs.User" user "User.Drawings")
		(19 "Cmts.User" user "User.Comments")
		(21 "Eco1.User" user "User.Eco1")
		(23 "Eco2.User" user "User.Eco2")
		(25 "Edge.Cuts" user "Board Geometry/Outline")
		(27 "Margin" user)
		(31 "F.CrtYd" user "Package Geometry/Place Bound Top")
		(29 "B.CrtYd" user "Package Geometry/Place Bound Bottom")
		(35 "F.Fab" user "Ref Des/Assembly Top")
		(33 "B.Fab" user "Ref Des/Assembly Bottom")
	)
	(footprint ""
		(layer "B.Cu")
		(at 42.855896 -55.297324 180)
		(property "Reference" "L7"
			(at 0 0 0)
			(layer "B.SilkS")
			(hide yes)
			(effects
				(font
					(size 1.27 1.27)
				)
				(justify mirror)
			)
		)
		(property "Value" ""
			(at 0 0 0)
			(layer "B.Fab")
			(effects
				(font
					(size 1.27 1.27)
				)
				(justify mirror)
			)
		)
		(duplicate_pad_numbers_are_jumpers no)
		(fp_line
			(start 1.27 0.5842)
			(end 1.27 -0.5842)
			(stroke
				(width 0.1524)
				(type default)
			)
			(layer "B.SilkS")
		)
		(fp_line
			(start 1.27 -0.5588)
			(end 1.27 -0.5842)
			(stroke
				(width 0.1524)
				(type default)
			)
			(layer "B.SilkS")
		)
		(fp_line
			(start 1.27 -0.5842)
			(end -1.27 -0.5842)
			(stroke
				(width 0.1524)
				(type default)
			)
			(layer "B.SilkS")
		)
		(fp_line
			(start 0.127 0.5842)
			(end 0.127 -0.5842)
			(stroke
				(width 0.1524)
				(type default)
			)
			(layer "B.SilkS")
		)
		(fp_line
			(start -0.127 0.5842)
			(end -0.127 -0.5842)
			(stroke
				(width 0.1524)
				(type default)
			)
			(layer "B.SilkS")
		)
		(fp_line
			(start -1.27 0.5842)
			(end 1.27 0.5842)
			(stroke
				(width 0.1524)
				(type default)
			)
			(layer "B.SilkS")
		)
		(fp_line
			(start -1.27 0.5842)
			(end -1.27 -0.5842)
			(stroke
				(width 0.1524)
				(type default)
			)
			(layer "B.SilkS")
		)
		(fp_line
			(start 1.194308 0.406654)
			(end 1.194308 -0.406654)
			(stroke
				(width 0.1)
				(type default)
			)
			(layer "B.Fab")
		)
		(fp_line
			(start 1.194308 -0.406654)
			(end 0.9144 -0.406654)
			(stroke
				(width 0.1)
				(type default)
			)
			(layer "B.Fab")
		)
		(fp_line
			(start 0.9144 0.508)
			(end 0.9144 0.406654)
			(stroke
				(width 0.1)
				(type default)
			)
			(layer "B.Fab")
		)
		(fp_line
			(start 0.9144 0.406654)
			(end 1.194308 0.406654)
			(stroke
				(width 0.1)
				(type default)
			)
			(layer "B.Fab")
		)
		(fp_line
			(start 0.9144 -0.406654)
			(end 0.9144 -0.508)
			(stroke
				(width 0.1)
				(type default)
			)
			(layer "B.Fab")
		)
		(fp_line
			(start 0.9144 -0.508)
			(end -0.9144 -0.508)
			(stroke
				(width 0.1)
				(type default)
			)
			(layer "B.Fab")
		)
		(fp_line
			(start -0.9144 0.508)
			(end 0.9144 0.508)
			(stroke
				(width 0.1)
				(type default)
			)
			(layer "B.Fab")
		)
		(fp_line
			(start -0.9144 0.4064)
			(end -0.9144 0.508)
			(stroke
				(width 0.1)
				(type default)
			)
			(layer "B.Fab")
		)
		(fp_line
			(start -0.9144 -0.406654)
			(end -1.1938 -0.406654)
			(stroke
				(width 0.1)
				(type default)
			)
			(layer "B.Fab")
		)
		(fp_line
			(start -0.9144 -0.508)
			(end -0.9144 -0.406654)
			(stroke
				(width 0.1)
				(type default)
			)
			(layer "B.Fab")
		)
		(fp_line
			(start -1.1938 0.4064)
			(end -0.9144 0.4064)
			(stroke
				(width 0.1)
				(type default)
			)
			(layer "B.Fab")
		)
		(fp_line
			(start -1.1938 -0.406654)
			(end -1.1938 0.4064)
			(stroke
				(width 0.1)
				(type default)
			)
			(layer "B.Fab")
		)
		(pad "1" smd rect
			(at 0.7366 0 90)
			(size 0.7112 0.8128)
			(layers "B.Cu" "B.Mask" "B.Paste")
			(net "P3V3_AUX")
		)
		(pad "2" smd rect
			(at -0.7366 0 90)
			(size 0.7112 0.8128)
			(layers "B.Cu" "B.Mask" "B.Paste")
			(net "P3V3_STBY_DACAV33")
		)
	)
	(footprint ""
		(layer "B.Cu")
		(at 19.853656 -93.98 180)
		(property "Reference" "C243"
			(at 0 0 0)
			(layer "B.SilkS")
			(hide yes)
			(effects
				(font
					(size 1.27 1.27)
				)
				(justify mirror)
			)
		)
		(property "Value" ""
			(at 0 0 0)
			(layer "B.Fab")
			(effects
				(font
					(size 1.27 1.27)
				)
				(justify mirror)
			)
		)
		(duplicate_pad_numbers_are_jumpers no)
		(fp_line
			(start 0.69215 0.2921)
			(end 0.69215 -0.2921)
			(stroke
				(width 0.1524)
				(type default)
			)
			(layer "B.SilkS")
		)
		(fp_line
			(start 0.69215 -0.2921)
			(end -0.69215 -0.2921)
			(stroke
				(width 0.1524)
				(type default)
			)
			(layer "B.SilkS")
		)
		(fp_line
			(start -0.69215 0.2921)
			(end 0.69215 0.2921)
			(stroke
				(width 0.1524)
				(type default)
			)
			(layer "B.SilkS")
		)
		(fp_line
			(start -0.69215 -0.2921)
			(end -0.69215 0.2921)
			(stroke
				(width 0.1524)
				(type default)
			)
			(layer "B.SilkS")
		)
		(fp_line
			(start 0.51435 0.2794)
			(end 0.51435 -0.2794)
			(stroke
				(width 0.1)
				(type default)
			)
			(layer "B.Fab")
		)
		(fp_line
			(start 0.51435 -0.2794)
			(end -0.51435 -0.2794)
			(stroke
				(width 0.1)
				(type default)
			)
			(layer "B.Fab")
		)
		(fp_line
			(start -0.51435 0.2794)
			(end 0.51435 0.2794)
			(stroke
				(width 0.1)
				(type default)
			)
			(layer "B.Fab")
		)
		(fp_line
			(start -0.51435 -0.2794)
			(end -0.51435 0.2794)
			(stroke
				(width 0.1)
				(type default)
			)
			(layer "B.Fab")
		)
		(pad "1" smd circle
			(at 0.40005 0)
			(size 0 0)
			(layers "B.Cu" "B.Mask" "B.Paste")
			(net "VCCIO1")
		)
		(pad "2" smd circle
			(at -0.40005 0)
			(size 0 0)
			(layers "B.Cu" "B.Mask" "B.Paste")
			(net "GND")
		)
		(zone
			(layer "B.Cu")
			(hatch none 0.5)
			(connect_pads
				(clearance 0)
			)
			(min_thickness 0.25)
			(keepout
				(tracks not_allowed)
				(vias allowed)
				(pads allowed)
				(copperpour not_allowed)
				(footprints allowed)
			)
			(placement
				(enabled no)
				(sheetname "")
			)
			(fill
				(thermal_gap 0.5)
				(thermal_bridge_width 0.5)
				(island_removal_mode 0)
			)
			(polygon
				(pts
					(xy 19.663156 -94.06763) (xy 19.754596 -94.125796) (xy 19.953986 -94.125796) (xy 20.044156 -94.06763)
					(xy 20.044156 -93.89237) (xy 19.953986 -93.83395) (xy 19.754596 -93.83395) (xy 19.663156 -93.892116)
				)
			)
		)
	)
)
